(kicad_pcb
	(version 20241229)
	(generator "pcbnew")
	(generator_version "9.0")
	(general
		(thickness 1.63)
		(legacy_teardrops no)
	)
	(paper "A4")
	(title_block
		(title "CM4 Baseboard")
		(date "2026-01-05")
		(rev "1.1.1")
		(company "Antmicro Ltd")
		(comment 1 "www.antmicro.com")
		(comment 9 "footprints 296-298 of 506")
	)
	(layers
		(0 "F.Cu" signal)
		(4 "In1.Cu" power)
		(6 "In2.Cu" power)
		(8 "In3.Cu" signal)
		(10 "In4.Cu" signal)
		(2 "B.Cu" signal)
		(9 "F.Adhes" user "F.Adhesive")
		(11 "B.Adhes" user "B.Adhesive")
		(13 "F.Paste" user)
		(15 "B.Paste" user)
		(5 "F.SilkS" user "F.Silkscreen")
		(7 "B.SilkS" user "B.Silkscreen")
		(1 "F.Mask" user)
		(3 "B.Mask" user)
		(17 "Dwgs.User" user "User.Drawings")
		(19 "Cmts.User" user "User.Comments")
		(21 "Eco1.User" user "User.Eco1")
		(23 "Eco2.User" user "User.Eco2")
		(25 "Edge.Cuts" user)
		(27 "Margin" user)
		(31 "F.CrtYd" user "F.Courtyard")
		(29 "B.CrtYd" user "B.Courtyard")
		(35 "F.Fab" user)
		(33 "B.Fab" user)
	)
	(footprint "antmicro-footprints:R_0402_1005Metric"
		(layer "F.Cu")
		(at 99.037962 131.8365 180)
		(descr "Resistor SMD 0402")
		(tags "resistor SMD 0402")
		(property "Reference" "R914"
			(at 0.66 -0.34 0)
			(layer "F.SilkS")
			(effects
				(font
					(size 0.7 0.7)
					(thickness 0.15)
				)
				(justify right bottom)
			)
		)
		(property "Value" "R_100k_0402"
			(at -1.011843 1.772047 0)
			(layer "F.Fab")
			(effects
				(font
					(size 0.7 0.7)
					(thickness 0.15)
				)
				(justify right bottom)
			)
		)
		(property "Datasheet" "https://www.bourns.com/docs/product-datasheets/cr.pdf"
			(at 0 0 180)
			(layer "F.Fab")
			(hide yes)
			(effects
				(font
					(size 1.27 1.27)
					(thickness 0.15)
				)
			)
		)
		(property "Manufacturer" "Bourns"
			(at 0 0 180)
			(unlocked yes)
			(layer "F.Fab")
			(hide yes)
			(effects
				(font
					(size 1 1)
					(thickness 0.15)
				)
			)
		)
		(property "MPN" "CR0402-FX-1003GLF"
			(at 0 0 180)
			(unlocked yes)
			(layer "F.Fab")
			(hide yes)
			(effects
				(font
					(size 1 1)
					(thickness 0.15)
				)
			)
		)
		(property "Val" "100k"
			(at 0 0 180)
			(unlocked yes)
			(layer "F.Fab")
			(hide yes)
			(effects
				(font
					(size 1 1)
					(thickness 0.15)
				)
			)
		)
		(property "License" "Apache-2.0"
			(at 0 0 180)
			(unlocked yes)
			(layer "F.Fab")
			(hide yes)
			(effects
				(font
					(size 1 1)
					(thickness 0.15)
				)
			)
		)
		(property "Author" "Antmicro"
			(at 0 0 180)
			(unlocked yes)
			(layer "F.Fab")
			(hide yes)
			(effects
				(font
					(size 1 1)
					(thickness 0.15)
				)
			)
		)
		(property "Tolerance" "1%"
			(at 0 0 180)
			(unlocked yes)
			(layer "F.Fab")
			(hide yes)
			(effects
				(font
					(size 1 1)
					(thickness 0.15)
				)
			)
		)
		(sheetname "/USB/")
		(sheetfile "usb.kicad_sch")
		(attr smd)
		(fp_rect
			(start -0.925 -0.47)
			(end 0.925 0.47)
			(stroke
				(width 0.05)
				(type default)
			)
			(fill no)
			(layer "F.CrtYd")
		)
		(fp_rect
			(start -0.5 -0.25)
			(end 0.5 0.25)
			(stroke
				(width 0.15)
				(type solid)
			)
			(fill no)
			(layer "F.Fab")
		)
		(fp_text user "Author: Antmicro"
			(at -0.95 4.169 180)
			(layer "F.Fab")
			(effects
				(font
					(size 0.7 0.7)
					(thickness 0.15)
				)
				(justify left bottom)
			)
		)
		(fp_text user "${REFERENCE}"
			(at -0.95 3.168 180)
			(layer "F.Fab")
			(effects
				(font
					(size 0.7 0.7)
					(thickness 0.15)
				)
				(justify left bottom)
			)
		)
		(fp_text user "License: Apache-2.0"
			(at -0.95 5.169 180)
			(layer "F.Fab")
			(effects
				(font
					(size 0.7 0.7)
					(thickness 0.15)
				)
				(justify left bottom)
			)
		)
		(pad "1" smd roundrect
			(at -0.48 0 180)
			(size 0.59 0.64)
			(layers "F.Cu" "F.Mask" "F.Paste")
			(roundrect_rratio 0.25)
			(net 28 "/USB/+5V_{CAP}")
			(pintype "passive")
		)
		(pad "2" smd roundrect
			(at 0.48 0 180)
			(size 0.59 0.64)
			(layers "F.Cu" "F.Mask" "F.Paste")
			(roundrect_rratio 0.25)
			(net 288 "/USB/USBA_OUT_EN")
			(pintype "passive")
		)
	)
	(footprint "antmicro-footprints:XDFN-2_1x0.60mm"
		(layer "F.Cu")
		(at 134.337962 125.9465 180)
		(property "Reference" "D203"
			(at 0.46 -1.495 180)
			(layer "F.SilkS")
			(effects
				(font
					(size 0.7 0.7)
					(thickness 0.15)
				)
				(justify left bottom)
			)
		)
		(property "Value" "TPD1E0B04_XDFN-2"
			(at 0 1.5 0)
			(layer "F.Fab")
			(effects
				(font
					(size 0.7 0.7)
					(thickness 0.15)
				)
				(justify right bottom)
			)
		)
		(property "Datasheet" "https://www.ti.com/general/docs/suppproductinfo.tsp?distId=26&gotoUrl=https://www.ti.com/lit/gpn/tpd1e0b04"
			(at 0 0 180)
			(layer "F.Fab")
			(hide yes)
			(effects
				(font
					(size 1.27 1.27)
					(thickness 0.15)
				)
			)
		)
		(property "MPN" "TPD1E0B04DPYR"
			(at 268.675924 251.893 0)
			(layer "F.Fab")
			(hide yes)
			(effects
				(font
					(size 1 1)
					(thickness 0.15)
				)
			)
		)
		(property "Manufacturer" "Texas Instruments"
			(at 268.675924 251.893 0)
			(layer "F.Fab")
			(hide yes)
			(effects
				(font
					(size 1 1)
					(thickness 0.15)
				)
			)
		)
		(property "Author" "Antmicro"
			(at 0 0 180)
			(unlocked yes)
			(layer "F.Fab")
			(hide yes)
			(effects
				(font
					(size 1 1)
					(thickness 0.15)
				)
			)
		)
		(property "License" "Apache-2.0"
			(at 0 0 180)
			(unlocked yes)
			(layer "F.Fab")
			(hide yes)
			(effects
				(font
					(size 1 1)
					(thickness 0.15)
				)
			)
		)
		(sheetname "/Compute module/")
		(sheetfile "compute-module.kicad_sch")
		(attr smd)
		(fp_rect
			(start -0.725 -0.475)
			(end 0.725 0.475)
			(stroke
				(width 0.05)
				(type solid)
			)
			(fill no)
			(layer "F.CrtYd")
		)
		(fp_rect
			(start -0.55 -0.35)
			(end 0.55 0.35)
			(stroke
				(width 0.15)
				(type solid)
			)
			(fill no)
			(layer "F.Fab")
		)
		(fp_text user "${REFERENCE}"
			(at -0.8 3.2 180)
			(layer "F.Fab")
			(effects
				(font
					(size 0.7 0.7)
					(thickness 0.15)
				)
				(justify left bottom)
			)
		)
		(fp_text user "Author: Antmicro"
			(at -0.8 4.4 180)
			(layer "F.Fab")
			(effects
				(font
					(size 0.7 0.7)
					(thickness 0.15)
				)
				(justify left bottom)
			)
		)
		(fp_text user "License: Apache-2.0"
			(at -0.8 5.6 180)
			(layer "F.Fab")
			(effects
				(font
					(size 0.7 0.7)
					(thickness 0.15)
				)
				(justify left bottom)
			)
		)
		(pad "1" smd roundrect
			(at -0.351 0 180)
			(size 0.3 0.5)
			(layers "F.Cu" "F.Mask" "F.Paste")
			(roundrect_rratio 0.25)
			(net 3 "GND")
			(pinfunction "C")
			(pintype "passive")
		)
		(pad "2" smd roundrect
			(at 0.349 0 180)
			(size 0.3 0.5)
			(layers "F.Cu" "F.Mask" "F.Paste")
			(roundrect_rratio 0.25)
			(net 2 "Net-(D203-A)")
			(pinfunction "A")
			(pintype "passive")
		)
	)
	(footprint "antmicro-footprints:SOT-23-3"
		(layer "F.Cu")
		(at 104.842962 150.592)
		(property "Reference" "Q204"
			(at -1.475 -1.6255 0)
			(layer "F.SilkS")
			(effects
				(font
					(size 0.7 0.7)
					(thickness 0.15)
				)
				(justify left bottom)
			)
		)
		(property "Value" "SSM3J332R"
			(at -1.9 2.7 0)
			(layer "F.Fab")
			(effects
				(font
					(size 0.7 0.7)
					(thickness 0.15)
				)
				(justify left bottom)
			)
		)
		(property "Datasheet" "https://www.mouser.com/datasheet/2/408/SSM3J332R_datasheet_en_20181015-1150575.pdf"
			(at 0 0 0)
			(layer "F.Fab")
			(hide yes)
			(effects
				(font
					(size 1.27 1.27)
					(thickness 0.15)
				)
			)
		)
		(property "MPN" "SSM3J332R,LF"
			(at 0 0 0)
			(unlocked yes)
			(layer "F.Fab")
			(hide yes)
			(effects
				(font
					(size 1 1)
					(thickness 0.15)
				)
			)
		)
		(property "Manufacturer" "Toshiba"
			(at 0 0 0)
			(unlocked yes)
			(layer "F.Fab")
			(hide yes)
			(effects
				(font
					(size 1 1)
					(thickness 0.15)
				)
			)
		)
		(property "Author" "Antmicro"
			(at 0 0 0)
			(unlocked yes)
			(layer "F.Fab")
			(hide yes)
			(effects
				(font
					(size 1 1)
					(thickness 0.15)
				)
			)
		)
		(property "License" "Apache-2.0"
			(at 0 0 0)
			(unlocked yes)
			(layer "F.Fab")
			(hide yes)
			(effects
				(font
					(size 1 1)
					(thickness 0.15)
				)
			)
		)
		(sheetname "/Compute module/")
		(sheetfile "compute-module.kicad_sch")
		(attr smd)
		(fp_line
			(start -1.45 -1.35)
			(end -0.85 -1.35)
			(stroke
				(width 0.15)
				(type solid)
			)
			(layer "F.SilkS")
		)
		(fp_line
			(start -0.85 -1.35)
			(end -0.7 -1.5)
			(stroke
				(width 0.15)
				(type solid)
			)
			(layer "F.SilkS")
		)
		(fp_line
			(start -0.7 1.5)
			(end -0.7 1.35)
			(stroke
				(width 0.15)
				(type solid)
			)
			(layer "F.SilkS")
		)
		(fp_line
			(start 0.7 -1.5)
			(end -0.7 -1.5)
			(stroke
				(width 0.15)
				(type solid)
			)
			(layer "F.SilkS")
		)
		(fp_line
			(start 0.7 -0.4)
			(end 0.7 -1.5)
			(stroke
				(width 0.15)
				(type solid)
			)
			(layer "F.SilkS")
		)
		(fp_line
			(start 0.7 0.4)
			(end 0.7 1.5)
			(stroke
				(width 0.15)
				(type solid)
			)
			(layer "F.SilkS")
		)
		(fp_line
			(start 0.7 1.5)
			(end -0.7 1.5)
			(stroke
				(width 0.15)
				(type solid)
			)
			(layer "F.SilkS")
		)
		(fp_line
			(start -1.75 -0.5)
			(end -1.75 -1.4)
			(stroke
				(width 0.05)
				(type solid)
			)
			(layer "F.CrtYd")
		)
		(fp_line
			(start -1.75 0.5)
			(end -0.85 0.5)
			(stroke
				(width 0.05)
				(type solid)
			)
			(layer "F.CrtYd")
		)
		(fp_line
			(start -1.75 1.4)
			(end -1.75 0.5)
			(stroke
				(width 0.05)
				(type solid)
			)
			(layer "F.CrtYd")
		)
		(fp_line
			(start -0.9 -1.6)
			(end -0.9 -1.4)
			(stroke
				(width 0.05)
				(type solid)
			)
			(layer "F.CrtYd")
		)
		(fp_line
			(start -0.9 -1.6)
			(end 0.825 -1.6)
			(stroke
				(width 0.05)
				(type solid)
			)
			(layer "F.CrtYd")
		)
		(fp_line
			(start -0.9 -1.4)
			(end -1.75 -1.4)
			(stroke
				(width 0.05)
				(type solid)
			)
			(layer "F.CrtYd")
		)
		(fp_line
			(start -0.85 -0.5)
			(end -1.75 -0.5)
			(stroke
				(width 0.05)
				(type solid)
			)
			(layer "F.CrtYd")
		)
		(fp_line
			(start -0.85 0.5)
			(end -0.85 -0.5)
			(stroke
				(width 0.05)
				(type solid)
			)
			(layer "F.CrtYd")
		)
		(fp_line
			(start -0.85 1.4)
			(end -1.75 1.4)
			(stroke
				(width 0.05)
				(type solid)
			)
			(layer "F.CrtYd")
		)
		(fp_line
			(start -0.85 1.65)
			(end -0.85 1.4)
			(stroke
				(width 0.05)
				(type solid)
			)
			(layer "F.CrtYd")
		)
		(fp_line
			(start 0.825 -1.6)
			(end 0.825 -0.45)
			(stroke
				(width 0.05)
				(type solid)
			)
			(layer "F.CrtYd")
		)
		(fp_line
			(start 0.825 -0.45)
			(end 1.75 -0.45)
			(stroke
				(width 0.05)
				(type solid)
			)
			(layer "F.CrtYd")
		)
		(fp_line
			(start 0.85 0.45)
			(end 0.85 1.65)
			(stroke
				(width 0.05)
				(type solid)
			)
			(layer "F.CrtYd")
		)
		(fp_line
			(start 0.85 1.65)
			(end -0.85 1.65)
			(stroke
				(width 0.05)
				(type solid)
			)
			(layer "F.CrtYd")
		)
		(fp_line
			(start 1.75 -0.45)
			(end 1.75 0.45)
			(stroke
				(width 0.05)
				(type solid)
			)
			(layer "F.CrtYd")
		)
		(fp_line
			(start 1.75 0.45)
			(end 0.85 0.45)
			(stroke
				(width 0.05)
				(type solid)
			)
			(layer "F.CrtYd")
		)
		(fp_line
			(start -0.712 -1.325)
			(end -0.712 1.523)
			(stroke
				(width 0.15)
				(type solid)
			)
			(layer "F.Fab")
		)
		(fp_line
			(start -0.712 1.519)
			(end 0.688 1.519)
			(stroke
				(width 0.15)
				(type solid)
			)
			(layer "F.Fab")
		)
		(fp_line
			(start -0.437 -1.526)
			(end -0.712 -1.325)
			(stroke
				(width 0.15)
				(type solid)
			)
			(layer "F.Fab")
		)
		(fp_line
			(start -0.437 -1.526)
			(end 0.688 -1.526)
			(stroke
				(width 0.15)
				(type solid)
			)
			(layer "F.Fab")
		)
		(fp_line
			(start 0.688 1.519)
			(end 0.688 -1.52)
			(stroke
				(width 0.15)
				(type solid)
			)
			(layer "F.Fab")
		)
		(fp_text user "Author: Antmicro"
			(at -1.837 5.3 0)
			(layer "F.Fab")
			(effects
				(font
					(size 0.7 0.7)
					(thickness 0.15)
				)
				(justify left bottom)
			)
		)
		(fp_text user "${REFERENCE}"
			(at -1.837 4 0)
			(layer "F.Fab")
			(effects
				(font
					(size 0.7 0.7)
					(thickness 0.15)
				)
				(justify left bottom)
			)
		)
		(fp_text user "License: Apache-2.0"
			(at -1.8 6.8 0)
			(layer "F.Fab")
			(effects
				(font
					(size 0.7 0.7)
					(thickness 0.15)
				)
				(justify left bottom)
			)
		)
		(pad "1" smd roundrect
			(at -1.1 -0.951)
			(size 1 0.6)
			(layers "F.Cu" "F.Mask" "F.Paste")
			(roundrect_rratio 0.15)
			(net 327 "Net-(Q201-D)")
			(pinfunction "G")
			(pintype "input")
		)
		(pad "2" smd roundrect
			(at -1.1 0.949)
			(size 1 0.6)
			(layers "F.Cu" "F.Mask" "F.Paste")
			(roundrect_rratio 0.15)
			(net 10 "+5V")
			(pinfunction "S")
			(pintype "passive")
		)
		(pad "3" smd roundrect
			(at 1.1 -0.0005)
			(size 1 0.6)
			(layers "F.Cu" "F.Mask" "F.Paste")
			(roundrect_rratio 0.15)
			(net 259 "/Compute module/Pf_5V.SCL")
			(pinfunction "D")
			(pintype "passive")
		)
	)
)
